(kicad_pcb
	(version 20241229)
	(generator "pcbnew")
	(generator_version "9.0")
	(general
		(thickness 1.599998)
		(legacy_teardrops no)
	)
	(paper "A4")
	(title_block
		(title "Artix - Datacenter Secure Control Module (DC-SCM)")
		(date "2024-11-06")
		(rev "1.1.3")
		(comment 9 "footprints 373-377 of 544")
	)
	(layers
		(0 "F.Cu" signal)
		(4 "In1.Cu" signal)
		(6 "In2.Cu" signal)
		(8 "In3.Cu" signal)
		(10 "In4.Cu" signal)
		(12 "In5.Cu" signal)
		(14 "In6.Cu" signal)
		(2 "B.Cu" signal)
		(9 "F.Adhes" user "F.Adhesive")
		(11 "B.Adhes" user "B.Adhesive")
		(13 "F.Paste" user)
		(15 "B.Paste" user)
		(5 "F.SilkS" user "F.Silkscreen")
		(7 "B.SilkS" user "B.Silkscreen")
		(1 "F.Mask" user)
		(3 "B.Mask" user)
		(17 "Dwgs.User" user "User.Drawings")
		(19 "Cmts.User" user "User.Comments")
		(21 "Eco1.User" user "User.Eco1")
		(23 "Eco2.User" user "User.Eco2")
		(25 "Edge.Cuts" user)
		(27 "Margin" user)
		(31 "F.CrtYd" user "F.Courtyard")
		(29 "B.CrtYd" user "B.Courtyard")
		(35 "F.Fab" user)
		(33 "B.Fab" user)
	)
	(footprint "antmicro-footprints:R_0402_1005Metric"
		(layer "B.Cu")
		(at 106.225 148.275 90)
		(descr "Resistor SMD 0402")
		(tags "resistor SMD 0402")
		(property "Reference" "R99"
			(at -2.926 0.375 90)
			(layer "B.SilkS")
			(effects
				(font
					(size 0.7 0.7)
					(thickness 0.15)
				)
				(justify right bottom mirror)
			)
		)
		(property "Value" "R_51R_0402"
			(at 0 -1.4 90)
			(layer "B.Fab")
			(effects
				(font
					(size 0.7 0.7)
					(thickness 0.15)
				)
				(justify right bottom mirror)
			)
		)
		(property "Datasheet" "https://www.bourns.com/docs/product-datasheets/cr.pdf"
			(at 0 0 90)
			(layer "F.Fab")
			(hide yes)
			(effects
				(font
					(size 1.27 1.27)
					(thickness 0.15)
				)
			)
		)
		(property "Description" "SMD Chip Resistor, 51 ohm, ± 1%, 63 mW, 0402 [1005 Metric], Thick Film, General Purpose"
			(at 0 0 90)
			(layer "F.Fab")
			(hide yes)
			(effects
				(font
					(size 1.27 1.27)
					(thickness 0.15)
				)
			)
		)
		(property "Author" "Antmicro"
			(at 254.5 42.05 0)
			(layer "B.Fab")
			(hide yes)
			(effects
				(font
					(size 1 1)
					(thickness 0.15)
				)
				(justify mirror)
			)
		)
		(property "License" "Apache-2.0"
			(at 254.5 42.05 0)
			(layer "B.Fab")
			(hide yes)
			(effects
				(font
					(size 1 1)
					(thickness 0.15)
				)
				(justify mirror)
			)
		)
		(property "MPN" "CR0402-FX-51R0GLF"
			(at 254.5 42.05 0)
			(layer "B.Fab")
			(hide yes)
			(effects
				(font
					(size 1 1)
					(thickness 0.15)
				)
				(justify mirror)
			)
		)
		(property "Manufacturer" "Bourns"
			(at 254.5 42.05 0)
			(layer "B.Fab")
			(hide yes)
			(effects
				(font
					(size 1 1)
					(thickness 0.15)
				)
				(justify mirror)
			)
		)
		(property "Tolerance" "1%"
			(at 254.5 42.05 0)
			(layer "B.Fab")
			(hide yes)
			(effects
				(font
					(size 1 1)
					(thickness 0.15)
				)
				(justify mirror)
			)
		)
		(property "Val" "51R"
			(at 254.5 42.05 0)
			(layer "B.Fab")
			(hide yes)
			(effects
				(font
					(size 1 1)
					(thickness 0.15)
				)
				(justify mirror)
			)
		)
		(sheetname "/DDR3/")
		(sheetfile "ddr3.kicad_sch")
		(attr smd exclude_from_pos_files exclude_from_bom dnp)
		(fp_rect
			(start -0.925 0.47)
			(end 0.925 -0.47)
			(stroke
				(width 0.05)
				(type default)
			)
			(fill no)
			(layer "B.CrtYd")
		)
		(fp_rect
			(start -0.5 0.25)
			(end 0.5 -0.25)
			(stroke
				(width 0.15)
				(type solid)
			)
			(fill no)
			(layer "B.Fab")
		)
		(pad "1" smd roundrect
			(at -0.48 0 90)
			(size 0.59 0.64)
			(layers "B.Cu" "B.Mask" "B.Paste")
			(roundrect_rratio 0.25)
			(net 109 "Net-(C63-Pad1)")
			(pintype "passive")
		)
		(pad "2" smd roundrect
			(at 0.48 0 90)
			(size 0.59 0.64)
			(layers "B.Cu" "B.Mask" "B.Paste")
			(roundrect_rratio 0.25)
			(net 479 "DDR3_CLK_P")
			(pintype "passive")
		)
	)
	(footprint "antmicro-footprints:C_1210_3225Metric"
		(layer "B.Cu")
		(at 112.8 102.2 180)
		(descr "Capacitor SMD 1210")
		(tags "capacitor SMD 1210")
		(property "Reference" "C93"
			(at -2.9 1 90)
			(layer "B.SilkS")
			(effects
				(font
					(size 0.7 0.7)
					(thickness 0.15)
				)
				(justify left bottom mirror)
			)
		)
		(property "Value" "C_47u_1210"
			(at 0 -2.749 0)
			(layer "B.Fab")
			(effects
				(font
					(size 0.7 0.7)
					(thickness 0.15)
				)
				(justify left bottom mirror)
			)
		)
		(property "Datasheet" "https://www.kemet.com/en/us/capacitors/product/C1210C476K8RACTU.html"
			(at 0 0 180)
			(layer "F.Fab")
			(hide yes)
			(effects
				(font
					(size 1.27 1.27)
					(thickness 0.15)
				)
			)
		)
		(property "Description" "SMD Multilayer Ceramic Capacitor, 47 µF, 10 V, 1210 [3225 Metric], ± 10%, X7R, C Series KEMET"
			(at 0 0 180)
			(layer "F.Fab")
			(hide yes)
			(effects
				(font
					(size 1.27 1.27)
					(thickness 0.15)
				)
			)
		)
		(property "Author" "Antmicro"
			(at 225.6 204.4 0)
			(layer "B.Fab")
			(hide yes)
			(effects
				(font
					(size 1 1)
					(thickness 0.15)
				)
				(justify mirror)
			)
		)
		(property "Dielectric" ""
			(at 225.6 204.4 0)
			(layer "B.Fab")
			(hide yes)
			(effects
				(font
					(size 1 1)
					(thickness 0.15)
				)
				(justify mirror)
			)
		)
		(property "License" "Apache-2.0"
			(at 225.6 204.4 0)
			(layer "B.Fab")
			(hide yes)
			(effects
				(font
					(size 1 1)
					(thickness 0.15)
				)
				(justify mirror)
			)
		)
		(property "MPN" "C1210C476K8RACTU"
			(at 225.6 204.4 0)
			(layer "B.Fab")
			(hide yes)
			(effects
				(font
					(size 1 1)
					(thickness 0.15)
				)
				(justify mirror)
			)
		)
		(property "Manufacturer" "KEMET"
			(at 225.6 204.4 0)
			(layer "B.Fab")
			(hide yes)
			(effects
				(font
					(size 1 1)
					(thickness 0.15)
				)
				(justify mirror)
			)
		)
		(property "Public" "False"
			(at 225.6 204.4 0)
			(layer "B.Fab")
			(hide yes)
			(effects
				(font
					(size 1 1)
					(thickness 0.15)
				)
				(justify mirror)
			)
		)
		(property "Val" "47u"
			(at 225.6 204.4 0)
			(layer "B.Fab")
			(hide yes)
			(effects
				(font
					(size 1 1)
					(thickness 0.15)
				)
				(justify mirror)
			)
		)
		(property "Voltage" ""
			(at 225.6 204.4 0)
			(layer "B.Fab")
			(hide yes)
			(effects
				(font
					(size 1 1)
					(thickness 0.15)
				)
				(justify mirror)
			)
		)
		(sheetname "/FPGA banks 13-16/")
		(sheetfile "fpga-banks-13-16.kicad_sch")
		(attr smd)
		(fp_line
			(start -0.3 1.39)
			(end 0.3 1.39)
			(stroke
				(width 0.15)
				(type solid)
			)
			(layer "B.SilkS")
		)
		(fp_line
			(start -0.3 -1.39)
			(end 0.3 -1.39)
			(stroke
				(width 0.15)
				(type solid)
			)
			(layer "B.SilkS")
		)
		(fp_rect
			(start -2.1 1.75)
			(end 2.1 -1.75)
			(stroke
				(width 0.05)
				(type solid)
			)
			(fill no)
			(layer "B.CrtYd")
		)
		(fp_rect
			(start -1.6 1.25)
			(end 1.6 -1.25)
			(stroke
				(width 0.15)
				(type solid)
			)
			(fill no)
			(layer "B.Fab")
		)
		(pad "1" smd rect
			(at -1.145 0 180)
			(size 1.52 3.05)
			(layers "B.Cu" "B.Mask" "B.Paste")
			(net 1 "GND")
			(pintype "passive")
		)
		(pad "2" smd rect
			(at 1.145 0 180)
			(size 1.52 3.05)
			(layers "B.Cu" "B.Mask" "B.Paste")
			(net 2 "VCC3V3")
			(pintype "passive")
		)
	)
	(footprint "antmicro-footprints:C_0402_1005Metric"
		(layer "B.Cu")
		(at 122.975 109.375 90)
		(descr "Capacitor SMD 0402")
		(tags "capacitor SMD 0402")
		(property "Reference" "C10"
			(at 0.86 0.425 90)
			(layer "B.SilkS")
			(effects
				(font
					(size 0.7 0.7)
					(thickness 0.15)
				)
				(justify right bottom mirror)
			)
		)
		(property "Value" "C_100n_0402"
			(at 0 -1.4 90)
			(layer "B.Fab")
			(effects
				(font
					(size 0.7 0.7)
					(thickness 0.15)
				)
				(justify right bottom mirror)
			)
		)
		(property "Datasheet" "https://www.murata.com/products/productdetail?partno=GRM155R61H104KE14%23"
			(at 0 0 90)
			(layer "F.Fab")
			(hide yes)
			(effects
				(font
					(size 1.27 1.27)
					(thickness 0.15)
				)
			)
		)
		(property "Description" "SMD Multilayer Ceramic Capacitor, 0.1 µF, 50 V, 0402 [1005 Metric], ± 10%, X5R, GRM Series"
			(at 0 0 90)
			(layer "F.Fab")
			(hide yes)
			(effects
				(font
					(size 1.27 1.27)
					(thickness 0.15)
				)
			)
		)
		(property "Author" "Antmicro"
			(at 232.35 -13.6 0)
			(layer "B.Fab")
			(hide yes)
			(effects
				(font
					(size 1 1)
					(thickness 0.15)
				)
				(justify mirror)
			)
		)
		(property "Dielectric" "X5R"
			(at 232.35 -13.6 0)
			(layer "B.Fab")
			(hide yes)
			(effects
				(font
					(size 1 1)
					(thickness 0.15)
				)
				(justify mirror)
			)
		)
		(property "License" "Apache-2.0"
			(at 232.35 -13.6 0)
			(layer "B.Fab")
			(hide yes)
			(effects
				(font
					(size 1 1)
					(thickness 0.15)
				)
				(justify mirror)
			)
		)
		(property "MPN" "GRM155R61H104KE14D"
			(at 232.35 -13.6 0)
			(layer "B.Fab")
			(hide yes)
			(effects
				(font
					(size 1 1)
					(thickness 0.15)
				)
				(justify mirror)
			)
		)
		(property "Manufacturer" "Murata"
			(at 232.35 -13.6 0)
			(layer "B.Fab")
			(hide yes)
			(effects
				(font
					(size 1 1)
					(thickness 0.15)
				)
				(justify mirror)
			)
		)
		(property "Val" "100n"
			(at 232.35 -13.6 0)
			(layer "B.Fab")
			(hide yes)
			(effects
				(font
					(size 1 1)
					(thickness 0.15)
				)
				(justify mirror)
			)
		)
		(property "Voltage" "50V"
			(at 232.35 -13.6 0)
			(layer "B.Fab")
			(hide yes)
			(effects
				(font
					(size 1 1)
					(thickness 0.15)
				)
				(justify mirror)
			)
		)
		(sheetname "/Interfaces/")
		(sheetfile "interfaces.kicad_sch")
		(attr smd)
		(fp_rect
			(start -0.925 0.47)
			(end 0.925 -0.47)
			(stroke
				(width 0.05)
				(type default)
			)
			(fill no)
			(layer "B.CrtYd")
		)
		(fp_line
			(start 0.504 -0.248)
			(end -0.494 -0.248)
			(stroke
				(width 0.15)
				(type solid)
			)
			(layer "B.Fab")
		)
		(fp_line
			(start -0.494 -0.248)
			(end -0.494 0.25)
			(stroke
				(width 0.15)
				(type solid)
			)
			(layer "B.Fab")
		)
		(fp_line
			(start 0.504 0.25)
			(end 0.504 -0.248)
			(stroke
				(width 0.15)
				(type solid)
			)
			(layer "B.Fab")
		)
		(fp_line
			(start -0.494 0.25)
			(end 0.504 0.25)
			(stroke
				(width 0.15)
				(type solid)
			)
			(layer "B.Fab")
		)
		(pad "1" smd roundrect
			(at -0.48 0 90)
			(size 0.59 0.64)
			(layers "B.Cu" "B.Mask" "B.Paste")
			(roundrect_rratio 0.25)
			(net 1 "GND")
			(pintype "passive")
		)
		(pad "2" smd roundrect
			(at 0.48 0 90)
			(size 0.59 0.64)
			(layers "B.Cu" "B.Mask" "B.Paste")
			(roundrect_rratio 0.25)
			(net 2 "VCC3V3")
			(pintype "passive")
		)
	)
	(footprint "antmicro-footprints:C_0402_1005Metric"
		(layer "B.Cu")
		(at 121.865 114.45 -90)
		(descr "Capacitor SMD 0402")
		(tags "capacitor SMD 0402")
		(property "Reference" "C11"
			(at 0.825 -0.31375 90)
			(layer "B.SilkS")
			(effects
				(font
					(size 0.7 0.7)
					(thickness 0.15)
				)
				(justify left bottom mirror)
			)
		)
		(property "Value" "C_100n_0402"
			(at 0 -1.4 90)
			(layer "B.Fab")
			(effects
				(font
					(size 0.7 0.7)
					(thickness 0.15)
				)
				(justify left bottom mirror)
			)
		)
		(property "Datasheet" "https://www.murata.com/products/productdetail?partno=GRM155R61H104KE14%23"
			(at 0 0 270)
			(layer "F.Fab")
			(hide yes)
			(effects
				(font
					(size 1.27 1.27)
					(thickness 0.15)
				)
			)
		)
		(property "Description" "SMD Multilayer Ceramic Capacitor, 0.1 µF, 50 V, 0402 [1005 Metric], ± 10%, X5R, GRM Series"
			(at 0 0 270)
			(layer "F.Fab")
			(hide yes)
			(effects
				(font
					(size 1.27 1.27)
					(thickness 0.15)
				)
			)
		)
		(property "Author" "Antmicro"
			(at 7.415 236.315 0)
			(layer "B.Fab")
			(hide yes)
			(effects
				(font
					(size 1 1)
					(thickness 0.15)
				)
				(justify mirror)
			)
		)
		(property "Dielectric" "X5R"
			(at 7.415 236.315 0)
			(layer "B.Fab")
			(hide yes)
			(effects
				(font
					(size 1 1)
					(thickness 0.15)
				)
				(justify mirror)
			)
		)
		(property "License" "Apache-2.0"
			(at 7.415 236.315 0)
			(layer "B.Fab")
			(hide yes)
			(effects
				(font
					(size 1 1)
					(thickness 0.15)
				)
				(justify mirror)
			)
		)
		(property "MPN" "GRM155R61H104KE14D"
			(at 7.415 236.315 0)
			(layer "B.Fab")
			(hide yes)
			(effects
				(font
					(size 1 1)
					(thickness 0.15)
				)
				(justify mirror)
			)
		)
		(property "Manufacturer" "Murata"
			(at 7.415 236.315 0)
			(layer "B.Fab")
			(hide yes)
			(effects
				(font
					(size 1 1)
					(thickness 0.15)
				)
				(justify mirror)
			)
		)
		(property "Val" "100n"
			(at 7.415 236.315 0)
			(layer "B.Fab")
			(hide yes)
			(effects
				(font
					(size 1 1)
					(thickness 0.15)
				)
				(justify mirror)
			)
		)
		(property "Voltage" "50V"
			(at 7.415 236.315 0)
			(layer "B.Fab")
			(hide yes)
			(effects
				(font
					(size 1 1)
					(thickness 0.15)
				)
				(justify mirror)
			)
		)
		(sheetname "/Interfaces/")
		(sheetfile "interfaces.kicad_sch")
		(attr smd)
		(fp_rect
			(start -0.925 0.47)
			(end 0.925 -0.47)
			(stroke
				(width 0.05)
				(type default)
			)
			(fill no)
			(layer "B.CrtYd")
		)
		(fp_line
			(start -0.494 0.25)
			(end 0.504 0.25)
			(stroke
				(width 0.15)
				(type solid)
			)
			(layer "B.Fab")
		)
		(fp_line
			(start 0.504 0.25)
			(end 0.504 -0.248)
			(stroke
				(width 0.15)
				(type solid)
			)
			(layer "B.Fab")
		)
		(fp_line
			(start -0.494 -0.248)
			(end -0.494 0.25)
			(stroke
				(width 0.15)
				(type solid)
			)
			(layer "B.Fab")
		)
		(fp_line
			(start 0.504 -0.248)
			(end -0.494 -0.248)
			(stroke
				(width 0.15)
				(type solid)
			)
			(layer "B.Fab")
		)
		(pad "1" smd roundrect
			(at -0.48 0 270)
			(size 0.59 0.64)
			(layers "B.Cu" "B.Mask" "B.Paste")
			(roundrect_rratio 0.25)
			(net 1 "GND")
			(pintype "passive")
		)
		(pad "2" smd roundrect
			(at 0.48 0 270)
			(size 0.59 0.64)
			(layers "B.Cu" "B.Mask" "B.Paste")
			(roundrect_rratio 0.25)
			(net 2 "VCC3V3")
			(pintype "passive")
		)
	)
	(footprint "antmicro-footprints:C_0402_1005Metric"
		(layer "B.Cu")
		(at 129.175 126.775 180)
		(descr "Capacitor SMD 0402")
		(tags "capacitor SMD 0402")
		(property "Reference" "C12"
			(at -1.125 0.575 0)
			(layer "B.SilkS")
			(effects
				(font
					(size 0.7 0.7)
					(thickness 0.15)
				)
				(justify left bottom mirror)
			)
		)
		(property "Value" "C_100n_0402"
			(at 0 -1.4 0)
			(layer "B.Fab")
			(effects
				(font
					(size 0.7 0.7)
					(thickness 0.15)
				)
				(justify left bottom mirror)
			)
		)
		(property "Datasheet" "https://www.murata.com/products/productdetail?partno=GRM155R61H104KE14%23"
			(at 0 0 180)
			(layer "F.Fab")
			(hide yes)
			(effects
				(font
					(size 1.27 1.27)
					(thickness 0.15)
				)
			)
		)
		(property "Description" "SMD Multilayer Ceramic Capacitor, 0.1 µF, 50 V, 0402 [1005 Metric], ± 10%, X5R, GRM Series"
			(at 0 0 180)
			(layer "F.Fab")
			(hide yes)
			(effects
				(font
					(size 1.27 1.27)
					(thickness 0.15)
				)
			)
		)
		(property "Author" "Antmicro"
			(at 258.35 253.55 0)
			(layer "B.Fab")
			(hide yes)
			(effects
				(font
					(size 1 1)
					(thickness 0.15)
				)
				(justify mirror)
			)
		)
		(property "Dielectric" "X5R"
			(at 258.35 253.55 0)
			(layer "B.Fab")
			(hide yes)
			(effects
				(font
					(size 1 1)
					(thickness 0.15)
				)
				(justify mirror)
			)
		)
		(property "License" "Apache-2.0"
			(at 258.35 253.55 0)
			(layer "B.Fab")
			(hide yes)
			(effects
				(font
					(size 1 1)
					(thickness 0.15)
				)
				(justify mirror)
			)
		)
		(property "MPN" "GRM155R61H104KE14D"
			(at 258.35 253.55 0)
			(layer "B.Fab")
			(hide yes)
			(effects
				(font
					(size 1 1)
					(thickness 0.15)
				)
				(justify mirror)
			)
		)
		(property "Manufacturer" "Murata"
			(at 258.35 253.55 0)
			(layer "B.Fab")
			(hide yes)
			(effects
				(font
					(size 1 1)
					(thickness 0.15)
				)
				(justify mirror)
			)
		)
		(property "Val" "100n"
			(at 258.35 253.55 0)
			(layer "B.Fab")
			(hide yes)
			(effects
				(font
					(size 1 1)
					(thickness 0.15)
				)
				(justify mirror)
			)
		)
		(property "Voltage" "50V"
			(at 258.35 253.55 0)
			(layer "B.Fab")
			(hide yes)
			(effects
				(font
					(size 1 1)
					(thickness 0.15)
				)
				(justify mirror)
			)
		)
		(sheetname "/Interfaces/")
		(sheetfile "interfaces.kicad_sch")
		(attr smd)
		(fp_rect
			(start -0.925 0.47)
			(end 0.925 -0.47)
			(stroke
				(width 0.05)
				(type default)
			)
			(fill no)
			(layer "B.CrtYd")
		)
		(fp_line
			(start 0.504 0.25)
			(end 0.504 -0.248)
			(stroke
				(width 0.15)
				(type solid)
			)
			(layer "B.Fab")
		)
		(fp_line
			(start 0.504 -0.248)
			(end -0.494 -0.248)
			(stroke
				(width 0.15)
				(type solid)
			)
			(layer "B.Fab")
		)
		(fp_line
			(start -0.494 0.25)
			(end 0.504 0.25)
			(stroke
				(width 0.15)
				(type solid)
			)
			(layer "B.Fab")
		)
		(fp_line
			(start -0.494 -0.248)
			(end -0.494 0.25)
			(stroke
				(width 0.15)
				(type solid)
			)
			(layer "B.Fab")
		)
		(pad "1" smd roundrect
			(at -0.48 0 180)
			(size 0.59 0.64)
			(layers "B.Cu" "B.Mask" "B.Paste")
			(roundrect_rratio 0.25)
			(net 1 "GND")
			(pintype "passive")
		)
		(pad "2" smd roundrect
			(at 0.48 0 180)
			(size 0.59 0.64)
			(layers "B.Cu" "B.Mask" "B.Paste")
			(roundrect_rratio 0.25)
			(net 2 "VCC3V3")
			(pintype "passive")
		)
	)
)
